(kicad_pcb
	(version 20260206)
	(generator "pcbnew")
	(generator_version "10.0")
	(general
		(thickness 1.6)
		(legacy_teardrops no)
	)
	(paper "A4")
	(title_block
		(title "baseboard — 13948-1b.1110WZS1818.brd")
		(comment 1 "Honey Badger (Wiwynn) / footprints 1058-1063 of 2523")
	)
	(layers
		(0 "F.Cu" signal "TOP")
		(4 "In1.Cu" signal "L2GND")
		(6 "In2.Cu" signal "L3")
		(8 "In3.Cu" signal "L4VCC")
		(10 "In4.Cu" signal "L5VCC")
		(12 "In5.Cu" signal "L6")
		(14 "In6.Cu" signal "L7GND")
		(2 "B.Cu" signal "BOTTOM")
		(9 "F.Adhes" user "F.Adhesive")
		(11 "B.Adhes" user "B.Adhesive")
		(13 "F.Paste" user "Package Geometry/Pastemask Top")
		(15 "B.Paste" user "Package Geometry/Pastemask Bottom")
		(5 "F.SilkS" user "Ref Des/Silkscreen Top")
		(7 "B.SilkS" user "Ref Des/Silkscreen Bottom")
		(1 "F.Mask" user "Board Geometry/Soldermask Top")
		(3 "B.Mask" user "Board Geometry/Soldermask Bottom")
		(17 "Dwgs.User" user "User.Drawings")
		(19 "Cmts.User" user "User.Comments")
		(21 "Eco1.User" user "User.Eco1")
		(23 "Eco2.User" user "User.Eco2")
		(25 "Edge.Cuts" user "Board Geometry/Outline")
		(27 "Margin" user)
		(31 "F.CrtYd" user "Package Geometry/Place Bound Top")
		(29 "B.CrtYd" user "Package Geometry/Place Bound Bottom")
		(35 "F.Fab" user "Ref Des/Assembly Top")
		(33 "B.Fab" user "Ref Des/Assembly Bottom")
	)
	(footprint ""
		(layer "F.Cu")
		(at 286.766 -161.544 180)
		(property "Reference" "R250"
			(at 0 0 180)
			(layer "F.SilkS")
			(hide yes)
			(effects
				(font
					(size 1.27 1.27)
				)
			)
		)
		(property "Value" "0R2J-2-GP"
			(at 0.064008 -3.993896 180)
			(unlocked yes)
			(layer "F.Fab")
			(hide yes)
			(effects
				(font
					(size 1.016 1.016)
					(thickness 0.1524)
				)
			)
		)
		(property "Device Type" "R402H16"
			(at 0.064008 -5.517896 180)
			(unlocked yes)
			(layer "F.Fab")
			(hide yes)
			(effects
				(font
					(size 1.016 1.016)
					(thickness 0.1524)
				)
			)
		)
		(duplicate_pad_numbers_are_jumpers no)
		(fp_line
			(start 0.508 -0.9398)
			(end -0.508 -0.9398)
			(stroke
				(width 0.1524)
				(type default)
			)
			(layer "F.SilkS")
		)
		(fp_line
			(start -0.508 -0.9398)
			(end -0.508 0.9398)
			(stroke
				(width 0.1524)
				(type default)
			)
			(layer "F.SilkS")
		)
		(fp_rect
			(start -0.508 0.9398)
			(end 0.508 -0.9398)
			(stroke
				(width 0)
				(type default)
			)
			(fill no)
			(layer "F.CrtYd")
		)
		(fp_rect
			(start -0.508 0.9398)
			(end 0.508 -0.9398)
			(stroke
				(width 0)
				(type default)
			)
			(fill no)
			(layer "F.Fab")
		)
		(pad "1" smd custom
			(at 0 -0.4445 180)
			(size 0.1397 0.1397)
			(layers "F.Cu" "F.Mask" "F.Paste")
			(net "SYS_PWRBTN_N")
			(options
				(clearance outline)
				(anchor circle)
			)
			(primitives
				(gr_poly
					(pts
						(arc
							(start -0.1778 -0.2794)
							(mid -0.249642 -0.249642)
							(end -0.2794 -0.1778)
						)
						(arc
							(start -0.2794 0.1778)
							(mid -0.249642 0.249642)
							(end -0.1778 0.2794)
						)
						(arc
							(start 0.1778 0.2794)
							(mid 0.249642 0.249642)
							(end 0.2794 0.1778)
						)
						(arc
							(start 0.2794 -0.1778)
							(mid 0.249642 -0.249642)
							(end 0.1778 -0.2794)
						)
					)
					(width 0)
					(fill yes)
				)
			)
		)
		(pad "2" smd custom
			(at 0 0.4445 180)
			(size 0.1397 0.1397)
			(layers "F.Cu" "F.Mask" "F.Paste")
			(net "SYS_PWRBTN_N_R")
			(options
				(clearance outline)
				(anchor circle)
			)
			(primitives
				(gr_poly
					(pts
						(arc
							(start -0.1778 -0.2794)
							(mid -0.249642 -0.249642)
							(end -0.2794 -0.1778)
						)
						(arc
							(start -0.2794 0.1778)
							(mid -0.249642 0.249642)
							(end -0.1778 0.2794)
						)
						(arc
							(start 0.1778 0.2794)
							(mid 0.249642 0.249642)
							(end 0.2794 0.1778)
						)
						(arc
							(start 0.2794 -0.1778)
							(mid 0.249642 -0.249642)
							(end 0.1778 -0.2794)
						)
					)
					(width 0)
					(fill yes)
				)
			)
		)
	)
	(footprint ""
		(layer "F.Cu")
		(at 268.351 -216.027 90)
		(property "Reference" "PC97"
			(at 0 0 90)
			(layer "F.SilkS")
			(hide yes)
			(effects
				(font
					(size 1.27 1.27)
				)
			)
		)
		(property "Value" "SC10U6D3V5KX-1GP"
			(at -0.0762 -6.1214 90)
			(unlocked yes)
			(layer "F.Fab")
			(hide yes)
			(effects
				(font
					(size 1.016 1.016)
					(thickness 0.1524)
				)
			)
		)
		(property "Device Type" "C805H54"
			(at -0.0762 -8.1534 90)
			(unlocked yes)
			(layer "F.Fab")
			(hide yes)
			(effects
				(font
					(size 1.016 1.016)
					(thickness 0.1524)
				)
			)
		)
		(duplicate_pad_numbers_are_jumpers no)
		(fp_line
			(start 0.635 0)
			(end -0.635 0)
			(stroke
				(width 0.508)
				(type default)
			)
			(layer "F.SilkS")
		)
		(fp_rect
			(start -0.9652 1.778)
			(end 0.9652 -1.778)
			(stroke
				(width 0)
				(type default)
			)
			(fill no)
			(layer "F.CrtYd")
		)
		(fp_poly
			(pts
				(xy -0.9652 -1.778) (xy 0.9652 -1.778) (xy 0.9652 1.778) (xy -0.9652 1.778)
			)
			(stroke
				(width 0)
				(type default)
			)
			(fill no)
			(layer "F.Fab")
		)
		(pad "1" smd rect
			(at 0 -0.9652 90)
			(size 1.397 1.143)
			(layers "F.Cu" "F.Mask" "F.Paste")
			(net "TPS74801_1V26_STBY_OUT")
		)
		(pad "2" smd rect
			(at 0 0.9652 90)
			(size 1.397 1.143)
			(layers "F.Cu" "F.Mask" "F.Paste")
			(net "GND")
		)
	)
	(footprint ""
		(layer "F.Cu")
		(at 96.540066 -2.029968 90)
		(property "Reference" "LED5"
			(at 0 0 90)
			(layer "F.SilkS")
			(hide yes)
			(effects
				(font
					(size 1.27 1.27)
				)
			)
		)
		(property "Value" "LED-B-77-GP-U3"
			(at -0.7112 -3.6068 90)
			(unlocked yes)
			(layer "F.Fab")
			(hide yes)
			(effects
				(font
					(size 1.016 1.016)
					(thickness 0.1524)
				)
			)
		)
		(property "Device Type" "LED3020AK-U2H44"
			(at -0.7112 -5.1308 90)
			(unlocked yes)
			(layer "F.Fab")
			(hide yes)
			(effects
				(font
					(size 1.016 1.016)
					(thickness 0.1524)
				)
			)
		)
		(duplicate_pad_numbers_are_jumpers no)
		(fp_line
			(start 0.8382 -2.4003)
			(end -0.8382 -2.4003)
			(stroke
				(width 0.1524)
				(type default)
			)
			(layer "F.SilkS")
		)
		(fp_line
			(start -0.8382 -2.4003)
			(end -0.8382 -1.31445)
			(stroke
				(width 0.1524)
				(type default)
			)
			(layer "F.SilkS")
		)
		(fp_line
			(start -0.8382 1.31445)
			(end -0.8382 2.4003)
			(stroke
				(width 0.1524)
				(type default)
			)
			(layer "F.SilkS")
		)
		(fp_line
			(start 0.8382 2.4003)
			(end 0.8382 -2.4003)
			(stroke
				(width 0.1524)
				(type default)
			)
			(layer "F.SilkS")
		)
		(fp_line
			(start -0.8382 2.4003)
			(end 0.8382 2.4003)
			(stroke
				(width 0.1524)
				(type default)
			)
			(layer "F.SilkS")
		)
		(fp_line
			(start 0.889 2.5273)
			(end -0.889 2.5273)
			(stroke
				(width 0.4064)
				(type default)
			)
			(layer "F.SilkS")
		)
		(fp_arc
			(start -0.8382 1.31445)
			(mid -1.85412 0)
			(end -0.8382 -1.31445)
			(stroke
				(width 0.1524)
				(type default)
			)
			(layer "F.SilkS")
		)
		(fp_poly
			(pts
				(xy -1.0922 2.6543) (xy -1.0922 1.49606) (xy -1.15189 1.4732) (xy -1.27254 1.41351) (xy -1.38557 1.34493)
				(xy -1.49098 1.26873) (xy -1.59258 1.18237) (xy -1.68656 1.08712) (xy -1.77165 0.98552) (xy -1.84785 0.87757)
				(xy -1.91516 0.76454) (xy -1.97358 0.64262) (xy -2.02057 0.5207) (xy -2.05867 0.3937) (xy -2.08534 0.26416)
				(xy -2.10185 0.13335) (xy -2.1082 0) (xy -2.10185 -0.13335) (xy -2.08534 -0.26416) (xy -2.05867 -0.3937)
				(xy -2.02057 -0.5207) (xy -1.97358 -0.64262) (xy -1.91516 -0.76454) (xy -1.84785 -0.87757) (xy -1.77165 -0.98552)
				(xy -1.68656 -1.08712) (xy -1.59258 -1.18237) (xy -1.49098 -1.26873) (xy -1.38557 -1.34493) (xy -1.27254 -1.41351)
				(xy -1.15189 -1.4732) (xy -1.0922 -1.49606) (xy -1.0922 -2.6543) (xy 1.0922 -2.6543) (xy 1.0922 2.6543)
			)
			(stroke
				(width 0)
				(type default)
			)
			(fill no)
			(layer "F.CrtYd")
		)
		(fp_poly
			(pts
				(xy -1.0922 2.6543) (xy -1.0922 1.49606) (xy -1.15189 1.4732) (xy -1.27254 1.41351) (xy -1.38557 1.34493)
				(xy -1.49098 1.26873) (xy -1.59258 1.18237) (xy -1.68656 1.08712) (xy -1.77165 0.98552) (xy -1.84785 0.87757)
				(xy -1.91516 0.76454) (xy -1.97358 0.64262) (xy -2.02057 0.5207) (xy -2.05867 0.3937) (xy -2.08534 0.26416)
				(xy -2.10185 0.13335) (xy -2.1082 0) (xy -2.10185 -0.13335) (xy -2.08534 -0.26416) (xy -2.05867 -0.3937)
				(xy -2.02057 -0.5207) (xy -1.97358 -0.64262) (xy -1.91516 -0.76454) (xy -1.84785 -0.87757) (xy -1.77165 -0.98552)
				(xy -1.68656 -1.08712) (xy -1.59258 -1.18237) (xy -1.49098 -1.26873) (xy -1.38557 -1.34493) (xy -1.27254 -1.41351)
				(xy -1.15189 -1.4732) (xy -1.0922 -1.49606) (xy -1.0922 -2.6543) (xy 1.0922 -2.6543) (xy 1.0922 2.6543)
			)
			(stroke
				(width 0)
				(type default)
			)
			(fill no)
			(layer "F.Fab")
		)
		(pad "A" smd rect
			(at 0 -1.57099 90)
			(size 1.143 1.143)
			(layers "F.Cu" "F.Mask" "F.Paste")
			(net "LED_PWR_N_R")
		)
		(pad "K" smd rect
			(at 0 1.57099 90)
			(size 1.143 1.143)
			(layers "F.Cu" "F.Mask" "F.Paste")
			(net "LED_PWR_N_ON")
		)
	)
	(footprint ""
		(layer "F.Cu")
		(at 220.68028 -91.02852)
		(property "Reference" "SR927"
			(at 0 0 0)
			(layer "F.SilkS")
			(hide yes)
			(effects
				(font
					(size 1.27 1.27)
				)
			)
		)
		(property "Value" "0R2J-2-GP"
			(at 0.064008 -3.993896 0)
			(unlocked yes)
			(layer "F.Fab")
			(hide yes)
			(effects
				(font
					(size 1.016 1.016)
					(thickness 0.1524)
				)
			)
		)
		(property "Device Type" "R402H16"
			(at 0.064008 -5.517896 0)
			(unlocked yes)
			(layer "F.Fab")
			(hide yes)
			(effects
				(font
					(size 1.016 1.016)
					(thickness 0.1524)
				)
			)
		)
		(duplicate_pad_numbers_are_jumpers no)
		(fp_line
			(start -0.508 -0.9398)
			(end -0.508 0.9398)
			(stroke
				(width 0.1524)
				(type default)
			)
			(layer "F.SilkS")
		)
		(fp_line
			(start 0.508 -0.9398)
			(end -0.508 -0.9398)
			(stroke
				(width 0.1524)
				(type default)
			)
			(layer "F.SilkS")
		)
		(fp_rect
			(start -0.508 0.9398)
			(end 0.508 -0.9398)
			(stroke
				(width 0)
				(type default)
			)
			(fill no)
			(layer "F.CrtYd")
		)
		(fp_rect
			(start -0.508 0.9398)
			(end 0.508 -0.9398)
			(stroke
				(width 0)
				(type default)
			)
			(fill no)
			(layer "F.Fab")
		)
		(pad "1" smd custom
			(at 0 -0.4445)
			(size 0.1397 0.1397)
			(layers "F.Cu" "F.Mask" "F.Paste")
			(net "IOC_UART_TX")
			(options
				(clearance outline)
				(anchor circle)
			)
			(primitives
				(gr_poly
					(pts
						(arc
							(start -0.1778 -0.2794)
							(mid -0.249642 -0.249642)
							(end -0.2794 -0.1778)
						)
						(arc
							(start -0.2794 0.1778)
							(mid -0.249642 0.249642)
							(end -0.1778 0.2794)
						)
						(arc
							(start 0.1778 0.2794)
							(mid 0.249642 0.249642)
							(end 0.2794 0.1778)
						)
						(arc
							(start 0.2794 -0.1778)
							(mid 0.249642 -0.249642)
							(end 0.1778 -0.2794)
						)
					)
					(width 0)
					(fill yes)
				)
			)
		)
		(pad "2" smd custom
			(at 0 0.4445)
			(size 0.1397 0.1397)
			(layers "F.Cu" "F.Mask" "F.Paste")
			(net "IOC_UART_R_TX")
			(options
				(clearance outline)
				(anchor circle)
			)
			(primitives
				(gr_poly
					(pts
						(arc
							(start -0.1778 -0.2794)
							(mid -0.249642 -0.249642)
							(end -0.2794 -0.1778)
						)
						(arc
							(start -0.2794 0.1778)
							(mid -0.249642 0.249642)
							(end -0.1778 0.2794)
						)
						(arc
							(start 0.1778 0.2794)
							(mid 0.249642 0.249642)
							(end 0.2794 0.1778)
						)
						(arc
							(start 0.2794 -0.1778)
							(mid 0.249642 -0.249642)
							(end 0.1778 -0.2794)
						)
					)
					(width 0)
					(fill yes)
				)
			)
		)
	)
	(footprint ""
		(layer "F.Cu")
		(at 159.766 -87.884)
		(property "Reference" "PTC6"
			(at 0 0 0)
			(layer "F.SilkS")
			(hide yes)
			(effects
				(font
					(size 1.27 1.27)
				)
			)
		)
		(property "Value" "SE470UF2VDM-GP"
			(at 0 -9.6012 0)
			(unlocked yes)
			(layer "F.Fab")
			(hide yes)
			(effects
				(font
					(size 1.016 1.016)
					(thickness 0.1524)
				)
			)
		)
		(property "Device Type" "CT7343H83"
			(at 0 -11.1252 0)
			(unlocked yes)
			(layer "F.Fab")
			(hide yes)
			(effects
				(font
					(size 1.016 1.016)
					(thickness 0.1524)
				)
			)
		)
		(duplicate_pad_numbers_are_jumpers no)
		(fp_line
			(start -2.286 -4.8768)
			(end -2.286 -2.032)
			(stroke
				(width 0.1524)
				(type default)
			)
			(layer "F.SilkS")
		)
		(fp_line
			(start -2.286 4.8768)
			(end -2.286 2.032)
			(stroke
				(width 0.1524)
				(type default)
			)
			(layer "F.SilkS")
		)
		(fp_line
			(start 2.1082 -4.699)
			(end -2.1082 -4.699)
			(stroke
				(width 0.508)
				(type default)
			)
			(layer "F.SilkS")
		)
		(fp_line
			(start 2.286 -4.8768)
			(end -2.286 -4.8768)
			(stroke
				(width 0.1524)
				(type default)
			)
			(layer "F.SilkS")
		)
		(fp_line
			(start 2.286 -2.032)
			(end 2.286 -4.8768)
			(stroke
				(width 0.1524)
				(type default)
			)
			(layer "F.SilkS")
		)
		(fp_line
			(start 2.286 2.032)
			(end 2.286 4.8768)
			(stroke
				(width 0.1524)
				(type default)
			)
			(layer "F.SilkS")
		)
		(fp_line
			(start 2.286 4.8768)
			(end -2.286 4.8768)
			(stroke
				(width 0.1524)
				(type default)
			)
			(layer "F.SilkS")
		)
		(fp_rect
			(start -2.1463 3.6449)
			(end 2.1463 -3.6449)
			(stroke
				(width 0)
				(type default)
			)
			(fill no)
			(layer "F.CrtYd")
		)
		(fp_poly
			(pts
				(xy -2.54 4.953) (xy -2.54 4.2926) (xy -3.81 4.2926) (xy -3.81 -4.2926) (xy -2.54 -4.2926) (xy -2.54 -4.953)
				(xy 2.54 -4.953) (xy 2.54 -4.2926) (xy 3.81 -4.2926) (xy 3.81 -1.6256) (xy 2.1463 -1.6256) (xy 2.1463 -3.6449)
				(xy -2.1463 -3.6449) (xy -2.1463 3.6449) (xy 2.1463 3.6449) (xy 2.1463 -1.6129) (xy 3.81 -1.6129)
				(xy 3.81 4.2926) (xy 2.54 4.2926) (xy 2.54 4.953)
			)
			(stroke
				(width 0)
				(type default)
			)
			(fill no)
			(layer "F.CrtYd")
		)
		(fp_rect
			(start -3.81 4.2926)
			(end -2.54 -4.2926)
			(stroke
				(width 0)
				(type default)
			)
			(fill no)
			(layer "F.Fab")
		)
		(fp_rect
			(start -2.54 4.953)
			(end 2.54 -4.953)
			(stroke
				(width 0)
				(type default)
			)
			(fill no)
			(layer "F.Fab")
		)
		(fp_rect
			(start 2.54 4.2926)
			(end 3.81 -4.2926)
			(stroke
				(width 0)
				(type default)
			)
			(fill no)
			(layer "F.Fab")
		)
		(pad "1" smd rect
			(at 0 -3.1496)
			(size 2.413 2.286)
			(layers "F.Cu" "F.Mask" "F.Paste")
			(net "P0V9_E")
		)
		(pad "2" smd rect
			(at 0 3.1496)
			(size 2.413 2.286)
			(layers "F.Cu" "F.Mask" "F.Paste")
			(net "GND")
		)
		(zone
			(layer "F.Cu")
			(hatch none 0.5)
			(connect_pads
				(clearance 0)
			)
			(min_thickness 0.25)
			(keepout
				(tracks allowed)
				(vias not_allowed)
				(pads allowed)
				(copperpour not_allowed)
				(footprints allowed)
			)
			(placement
				(enabled no)
				(sheetname "")
			)
			(fill
				(thermal_gap 0.5)
				(thermal_bridge_width 0.5)
				(island_removal_mode 0)
			)
			(polygon
				(pts
					(xy 158.2547 -83.2866) (xy 161.2773 -83.2866) (xy 161.2773 -86.1822) (xy 161.2773 -86.5124) (xy 158.2547 -86.5124)
					(xy 158.2547 -86.1822)
				)
			)
		)
		(zone
			(layer "F.Cu")
			(hatch none 0.5)
			(connect_pads
				(clearance 0)
			)
			(min_thickness 0.25)
			(keepout
				(tracks allowed)
				(vias not_allowed)
				(pads allowed)
				(copperpour not_allowed)
				(footprints allowed)
			)
			(placement
				(enabled no)
				(sheetname "")
			)
			(fill
				(thermal_gap 0.5)
				(thermal_bridge_width 0.5)
				(island_removal_mode 0)
			)
			(polygon
				(pts
					(xy 161.2773 -89.5731) (xy 161.2773 -92.4814) (xy 158.2547 -92.4814) (xy 158.2547 -89.5858) (xy 158.2547 -89.2556)
					(xy 161.2773 -89.2556)
				)
			)
		)
	)
	(footprint ""
		(layer "F.Cu")
		(at 160.02 -148.336 -90)
		(property "Reference" "SR726"
			(at 0 0 270)
			(layer "F.SilkS")
			(hide yes)
			(effects
				(font
					(size 1.27 1.27)
				)
			)
		)
		(property "Value" "4K7R2F-GP"
			(at 0.064008 -3.993896 270)
			(unlocked yes)
			(layer "F.Fab")
			(hide yes)
			(effects
				(font
					(size 1.016 1.016)
					(thickness 0.1524)
				)
			)
		)
		(property "Device Type" "R402H16"
			(at 0.064008 -5.517896 270)
			(unlocked yes)
			(layer "F.Fab")
			(hide yes)
			(effects
				(font
					(size 1.016 1.016)
					(thickness 0.1524)
				)
			)
		)
		(duplicate_pad_numbers_are_jumpers no)
		(fp_line
			(start -0.508 -0.9398)
			(end -0.508 0.9398)
			(stroke
				(width 0.1524)
				(type default)
			)
			(layer "F.SilkS")
		)
		(fp_line
			(start 0.508 -0.9398)
			(end -0.508 -0.9398)
			(stroke
				(width 0.1524)
				(type default)
			)
			(layer "F.SilkS")
		)
		(fp_rect
			(start -0.508 0.9398)
			(end 0.508 -0.9398)
			(stroke
				(width 0)
				(type default)
			)
			(fill no)
			(layer "F.CrtYd")
		)
		(fp_rect
			(start -0.508 0.9398)
			(end 0.508 -0.9398)
			(stroke
				(width 0)
				(type default)
			)
			(fill no)
			(layer "F.Fab")
		)
		(pad "1" smd custom
			(at 0 -0.4445 270)
			(size 0.1397 0.1397)
			(layers "F.Cu" "F.Mask" "F.Paste")
			(net "IOC_P3V3_SCL_14")
			(options
				(clearance outline)
				(anchor circle)
			)
			(primitives
				(gr_poly
					(pts
						(arc
							(start -0.1778 -0.2794)
							(mid -0.249642 -0.249642)
							(end -0.2794 -0.1778)
						)
						(arc
							(start -0.2794 0.1778)
							(mid -0.249642 0.249642)
							(end -0.1778 0.2794)
						)
						(arc
							(start 0.1778 0.2794)
							(mid 0.249642 0.249642)
							(end 0.2794 0.1778)
						)
						(arc
							(start 0.2794 -0.1778)
							(mid 0.249642 -0.249642)
							(end 0.1778 -0.2794)
						)
					)
					(width 0)
					(fill yes)
				)
			)
		)
		(pad "2" smd custom
			(at 0 0.4445 270)
			(size 0.1397 0.1397)
			(layers "F.Cu" "F.Mask" "F.Paste")
			(net "P3V3")
			(options
				(clearance outline)
				(anchor circle)
			)
			(primitives
				(gr_poly
					(pts
						(arc
							(start -0.1778 -0.2794)
							(mid -0.249642 -0.249642)
							(end -0.2794 -0.1778)
						)
						(arc
							(start -0.2794 0.1778)
							(mid -0.249642 0.249642)
							(end -0.1778 0.2794)
						)
						(arc
							(start 0.1778 0.2794)
							(mid 0.249642 0.249642)
							(end 0.2794 0.1778)
						)
						(arc
							(start 0.2794 -0.1778)
							(mid 0.249642 -0.249642)
							(end 0.1778 -0.2794)
						)
					)
					(width 0)
					(fill yes)
				)
			)
		)
	)
)
